# T6G (Grand Teton) — schematic netlist excerpt (pin names and nets, part order shuffled) for the footprints in the layout excerpt that follows; sources: Cadence DE-HDL packaged netlist, KiCad conversion of 04192023_DAF0TMB3IC0_F0TG_MB_C_brd_V02_OCP.brd

R3174  Q_RES  10K 1% CHIP  pkg 0402LF  page 137 : A = SGPIO_OCP_V3_2_DATAIN ; B = P3V3_OCP_V3_2
R2725  Q_RES  0 5% CHIP  pkg 0402LF  page 248 : A = I3C_BMC_SWB_R_SCL ; B = I3C_BMC_SWB_BUF_R_SCL

(kicad_pcb
	(version 20260206)
	(generator "pcbnew")
	(generator_version "10.0")
	(general
		(thickness 1.6)
		(legacy_teardrops no)
	)
	(paper "A4")
	(title_block
		(title "04192023_DAF0TMB3IC0_F0TG_MB_C_brd_V02_OCP.brd")
		(comment 1 "Grand Teton / footprints 7543-7544 of 8354")
	)
	(layers
		(0 "F.Cu" signal "TOP")
		(4 "In1.Cu" signal "GND")
		(6 "In2.Cu" signal "IN1")
		(8 "In3.Cu" signal "GND1")
		(10 "In4.Cu" signal "IN2")
		(12 "In5.Cu" signal "GND2")
		(14 "In6.Cu" signal "IN3")
		(16 "In7.Cu" signal "GND3")
		(18 "In8.Cu" signal "VCC")
		(20 "In9.Cu" signal "VCC1")
		(22 "In10.Cu" signal "GND4")
		(24 "In11.Cu" signal "IN4")
		(26 "In12.Cu" signal "GND5")
		(28 "In13.Cu" signal "IN5")
		(30 "In14.Cu" signal "GND6")
		(32 "In15.Cu" signal "IN6")
		(34 "In16.Cu" signal "GND7")
		(2 "B.Cu" signal "BOTTOM")
		(9 "F.Adhes" user "F.Adhesive")
		(11 "B.Adhes" user "B.Adhesive")
		(13 "F.Paste" user "Package Geometry/Pastemask Top")
		(15 "B.Paste" user "Package Geometry/Pastemask Bottom")
		(5 "F.SilkS" user "Ref Des/Silkscreen Top")
		(7 "B.SilkS" user "Ref Des/Silkscreen Bottom")
		(1 "F.Mask" user "Board Geometry/Soldermask Top")
		(3 "B.Mask" user "Board Geometry/Soldermask Bottom")
		(17 "Dwgs.User" user "User.Drawings")
		(19 "Cmts.User" user "User.Comments")
		(21 "Eco1.User" user "User.Eco1")
		(23 "Eco2.User" user "User.Eco2")
		(25 "Edge.Cuts" user "Board Geometry/Outline")
		(27 "Margin" user)
		(31 "F.CrtYd" user "Package Geometry/Place Bound Top")
		(29 "B.CrtYd" user "Package Geometry/Place Bound Bottom")
		(35 "F.Fab" user "Ref Des/Assembly Top")
		(33 "B.Fab" user "Ref Des/Assembly Bottom")
	)
	(footprint ""
		(layer "B.Cu")
		(at 75.473814 -9.50468 180)
		(property "Reference" "R3174"
			(at 0 0 0)
			(layer "B.SilkS")
			(hide yes)
			(effects
				(font
					(size 1.27 1.27)
				)
				(justify mirror)
			)
		)
		(property "Value" ""
			(at 0 0 0)
			(layer "B.Fab")
			(effects
				(font
					(size 1.27 1.27)
				)
				(justify mirror)
			)
		)
		(duplicate_pad_numbers_are_jumpers no)
		(fp_line
			(start 0.7874 0.4064)
			(end 0.7874 -0.4064)
			(stroke
				(width 0.1524)
				(type default)
			)
			(layer "B.SilkS")
		)
		(fp_line
			(start 0.7874 -0.4064)
			(end -0.7874 -0.4064)
			(stroke
				(width 0.1524)
				(type default)
			)
			(layer "B.SilkS")
		)
		(fp_line
			(start -0.7874 0.4064)
			(end 0.7874 0.4064)
			(stroke
				(width 0.1524)
				(type default)
			)
			(layer "B.SilkS")
		)
		(fp_line
			(start -0.7874 -0.4064)
			(end -0.7874 0.4064)
			(stroke
				(width 0.1524)
				(type default)
			)
			(layer "B.SilkS")
		)
		(fp_line
			(start 0.67945 0.3048)
			(end 0.67945 -0.305054)
			(stroke
				(width 0.1)
				(type default)
			)
			(layer "B.Fab")
		)
		(fp_line
			(start 0.67945 -0.305054)
			(end 0.12065 -0.305054)
			(stroke
				(width 0.1)
				(type default)
			)
			(layer "B.Fab")
		)
		(fp_line
			(start 0.12065 0.3048)
			(end 0.67945 0.3048)
			(stroke
				(width 0.1)
				(type default)
			)
			(layer "B.Fab")
		)
		(fp_line
			(start 0.12065 0.2794)
			(end 0.12065 0.3048)
			(stroke
				(width 0.1)
				(type default)
			)
			(layer "B.Fab")
		)
		(fp_line
			(start 0.12065 -0.2794)
			(end -0.12065 -0.2794)
			(stroke
				(width 0.1)
				(type default)
			)
			(layer "B.Fab")
		)
		(fp_line
			(start 0.12065 -0.305054)
			(end 0.12065 -0.2794)
			(stroke
				(width 0.1)
				(type default)
			)
			(layer "B.Fab")
		)
		(fp_line
			(start -0.120396 0.3048)
			(end -0.120396 0.2794)
			(stroke
				(width 0.1)
				(type default)
			)
			(layer "B.Fab")
		)
		(fp_line
			(start -0.120396 0.2794)
			(end 0.12065 0.2794)
			(stroke
				(width 0.1)
				(type default)
			)
			(layer "B.Fab")
		)
		(fp_line
			(start -0.12065 -0.2794)
			(end -0.12065 -0.3048)
			(stroke
				(width 0.1)
				(type default)
			)
			(layer "B.Fab")
		)
		(fp_line
			(start -0.12065 -0.3048)
			(end -0.67945 -0.3048)
			(stroke
				(width 0.1)
				(type default)
			)
			(layer "B.Fab")
		)
		(fp_line
			(start -0.67945 0.3048)
			(end -0.120396 0.3048)
			(stroke
				(width 0.1)
				(type default)
			)
			(layer "B.Fab")
		)
		(fp_line
			(start -0.67945 -0.3048)
			(end -0.67945 0.3048)
			(stroke
				(width 0.1)
				(type default)
			)
			(layer "B.Fab")
		)
		(pad "1" smd circle
			(at 0.40005 0)
			(size 0 0)
			(layers "B.Cu" "B.Mask" "B.Paste")
			(net "SGPIO_OCP_V3_2_DATAIN")
		)
		(pad "2" smd circle
			(at -0.40005 0)
			(size 0 0)
			(layers "B.Cu" "B.Mask" "B.Paste")
			(net "P3V3_OCP_V3_2")
		)
	)
	(footprint ""
		(layer "B.Cu")
		(at 286.893 -425.958 -90)
		(property "Reference" "R2725"
			(at 0 0 90)
			(layer "B.SilkS")
			(hide yes)
			(effects
				(font
					(size 1.27 1.27)
				)
				(justify mirror)
			)
		)
		(property "Value" ""
			(at 0 0 90)
			(layer "B.Fab")
			(effects
				(font
					(size 1.27 1.27)
				)
				(justify mirror)
			)
		)
		(duplicate_pad_numbers_are_jumpers no)
		(fp_line
			(start -0.7874 0.4064)
			(end 0.7874 0.4064)
			(stroke
				(width 0.1524)
				(type default)
			)
			(layer "B.SilkS")
		)
		(fp_line
			(start 0.7874 0.4064)
			(end 0.7874 -0.4064)
			(stroke
				(width 0.1524)
				(type default)
			)
			(layer "B.SilkS")
		)
		(fp_line
			(start -0.7874 -0.4064)
			(end -0.7874 0.4064)
			(stroke
				(width 0.1524)
				(type default)
			)
			(layer "B.SilkS")
		)
		(fp_line
			(start 0.7874 -0.4064)
			(end -0.7874 -0.4064)
			(stroke
				(width 0.1524)
				(type default)
			)
			(layer "B.SilkS")
		)
		(fp_line
			(start -0.67945 0.3048)
			(end -0.120396 0.3048)
			(stroke
				(width 0.1)
				(type default)
			)
			(layer "B.Fab")
		)
		(fp_line
			(start -0.120396 0.3048)
			(end -0.120396 0.2794)
			(stroke
				(width 0.1)
				(type default)
			)
			(layer "B.Fab")
		)
		(fp_line
			(start 0.12065 0.3048)
			(end 0.67945 0.3048)
			(stroke
				(width 0.1)
				(type default)
			)
			(layer "B.Fab")
		)
		(fp_line
			(start 0.67945 0.3048)
			(end 0.67945 -0.305054)
			(stroke
				(width 0.1)
				(type default)
			)
			(layer "B.Fab")
		)
		(fp_line
			(start -0.120396 0.2794)
			(end 0.12065 0.2794)
			(stroke
				(width 0.1)
				(type default)
			)
			(layer "B.Fab")
		)
		(fp_line
			(start 0.12065 0.2794)
			(end 0.12065 0.3048)
			(stroke
				(width 0.1)
				(type default)
			)
			(layer "B.Fab")
		)
		(fp_line
			(start -0.12065 -0.2794)
			(end -0.12065 -0.3048)
			(stroke
				(width 0.1)
				(type default)
			)
			(layer "B.Fab")
		)
		(fp_line
			(start 0.12065 -0.2794)
			(end -0.12065 -0.2794)
			(stroke
				(width 0.1)
				(type default)
			)
			(layer "B.Fab")
		)
		(fp_line
			(start -0.67945 -0.3048)
			(end -0.67945 0.3048)
			(stroke
				(width 0.1)
				(type default)
			)
			(layer "B.Fab")
		)
		(fp_line
			(start -0.12065 -0.3048)
			(end -0.67945 -0.3048)
			(stroke
				(width 0.1)
				(type default)
			)
			(layer "B.Fab")
		)
		(fp_line
			(start 0.12065 -0.305054)
			(end 0.12065 -0.2794)
			(stroke
				(width 0.1)
				(type default)
			)
			(layer "B.Fab")
		)
		(fp_line
			(start 0.67945 -0.305054)
			(end 0.12065 -0.305054)
			(stroke
				(width 0.1)
				(type default)
			)
			(layer "B.Fab")
		)
		(pad "1" smd circle
			(at 0.40005 0 90)
			(size 0 0)
			(layers "B.Cu" "B.Mask" "B.Paste")
			(net "I3C_BMC_SWB_R_SCL")
		)
		(pad "2" smd circle
			(at -0.40005 0 90)
			(size 0 0)
			(layers "B.Cu" "B.Mask" "B.Paste")
			(net "I3C_BMC_SWB_BUF_R_SCL")
		)
	)
)
